FILE_TYPE = MULTI_PHYS_TABLE;

PART 'MPQ8633AGLEC807Z'

{========================================================================================}
:VALUE                | PART_TYPE | MATERIAL | PART_NUMBER    = STANDARD    | LIFECYCLE     | PART_NUMBER   | JEDEC_TYPE  | DESCRIPTION                           | MANUFTR | MANUF_PN             | RD_CMPLS_LVL | CMPLS_LVL | FROM_PJ    | CLASS | DIP_SMD | DATA                         | EE_CHECK_LIST | FP_ECN | PSL | CREATOR | STATUS | MSD       | ESD_CDM | ESD_HBM | ESD_MM | PIN_LENGTH_SHORT_PIN | PIN_LENGTH_LONG_PIN | CREATEDAY  ;
{========================================================================================}
 'MPQ8633AGLE-C807-Z' | 'SMLF'    | 'IC'     | 'AL008633007'(!) = ''               | ''               | 'AL008633007' |'QFN14_4X3'| 'IC CTRL(21P)MPQ8633AGLE-C807-Z(QFN)' | 'MPS'   | 'MPQ8633AGLE-C807-Z' | 'EP(V1)'     | ''        | 'F0B-HANK' | 'IC'  | ''      | 'MPS_MPQ8633AGLE-C807-Z.pdf' | ''            | ''     | ''  | ''      | ''     | 'Level-2' | '0'     | '0'     | '00'   | '0 MILS'             | '0 MILS'            | '20180613'
 'MPQ8633AGLE-C807-Z' | 'SMLF'    | 'EMPTY'  | 'AL008633007'(!) = ''               | ''               | 'AL008633007' |'QFN14_4X3'| 'IC CTRL(21P)MPQ8633AGLE-C807-Z(QFN)' | 'MPS'   | 'MPQ8633AGLE-C807-Z' | 'EP(V1)'     | ''        | 'F0B-HANK' | 'IC'  | ''      | 'MPS_MPQ8633AGLE-C807-Z.pdf' | ''            | ''     | ''  | ''      | ''     | 'Level-2' | '0'     | '0'     | '00'   | '0 MILS'             | '0 MILS'            | '20180613'

END_PART

END.

